# PCBA Level ME_MP.xlsx — 工作表1 (spreadsheet-other)
| Level | Parent Number | Part Number | Description | Green Factor | Life Cycle State | Manufacturer | Manufacturer Part Number | Source | BOM Usage | M/P Code | S/D | Qty | UoM | Location |
| 16315D-SD |  |  |  |  |  |  |  |  |  |  |  |  |  |  |
| 2 |  | 086.000BF.0G20 | SCRW #2-56_L3_8_INCH 577-0014-000 | R2_C; | Released | TBD |  | Single |  | Purchase | DIP | 1 | PCS |  |
| 2 |  | B42.01101.0001 | GUIDE PIN 914-3000-00A | R2_C; | Released | TBD |  | Single |  | Purchase | DIP | 1 | PCS |  |
| 2 |  | B42.0111I.1001 | CVR XCEDE PWR JX410-50728 MP | R2_C; | Released | TBD |  | Single |  | Purchase | DIP | 1 | PCS |  |
| 2 |  | B42.0111M.1001 | CVR XCEDE SIGNAL JX412-50282 MP | R2_C; | Released | TBD |  | Single |  | Purchase | DIP | 1 | PCS |  |
| 2 |  | B42.0111N.1001 | CVR XCEDE SIGNAL JX430-50035 MP | R2_C; | Released | TBD |  | Single |  | Purchase | DIP | 2 | PCS |  |
| 3 |  | 087.71242.0465 | NUT TPM M3*0.5*L6 NI EVT | R2_SA;HF_SA; | Released | TBD |  | Single |  | Purchase | SMT | 8 | PCS | NUT1 NUT2 NUT3 NUT4 NUT5 NUT6 NUT7 NUT8 |
| 2 |  | 086.000LQ.0543 | THUMB SCREW PRESSFIT M3 L3 BC | R2_C; | Released | FIVETECH | 27-141-201-5 | Single |  | Purchase | DIP | 2 | PCS |  |
| 16316-SD |  |  |  |  |  |  |  |  |  |  |  |  |  |  |
| 2 |  | B34.0110S.0001 | HSINK 50X40X30_PUSHPIN_PAD SPONGE, CCI | R2_C;HF_C; | Released | CCI | TBD | Single |  | Purchase | DIP | 1 | PCS |  |
| 2 |  | B34.0110T.0001 | HSINK 64X50X30_PUSHPIN_PAD SPONGE, CCI | R2_C;HF_C; | Released | CCI | TBD | Single |  | Purchase | DIP | 1 | PCS |  |
| 2 |  | YAS0-00054-000$001 | SCREW TAPPING PAN M2 L5 BLUE ZN CR3+ | R2_SA; | Released | WENHAO | TBD | Single |  | Purchase | DIP | 2 | PCS |  |
| 2 |  | B42.0111G.0011 | LATCH SCC R BRYCE CANYON MP | R2_C; | Released | TBD |  | Single |  | Purchase | DIP | 1 | PCS |  |
| 2 |  | B42.0111H.0011 | LATCH SCC L BRYCE CANYON MP | R2_C; | Released | TBD |  | Single |  | Purchase | DIP | 1 | PCS |  |
| 16317-SD |  |  |  |  |  |  |  |  |  |  |  |  |  |  |
| 2 |  | 086.000BF.0G20 | SCRW #2-56_L3_8_INCH 577-0014-000 | R2_C; | Released | TBD |  | Single |  | Purchase | DIP | 1 | PCS |  |
| 2 |  | B42.01101.0001 | GUIDE PIN 914-3000-00A | R2_C; | Released | TBD |  | Single |  | Purchase | DIP | 1 | PCS |  |
| 2 |  | B42.0111J.1001 | CVR XCEDE PWR JX412-50194 MP | R2_C; | Released | TBD |  | Single |  | Purchase | DIP | 1 | PCS |  |
| 2 |  | B42.0111L.1001 | CVR XCEDE SIGNAL JX410-50839 MP | R2_C; | Released | TBD |  | Single |  | Purchase | DIP | 1 | PCS |  |
| 2 |  | 086.1A554.0140 | SCRW PAN M3X0.5 L14 NI NYLOK | R2_C; | Released | TBD |  | Single |  | Purchase | DIP | 2 | PCS |  |
| 2 |  | 87.41242.420 | NUT M3 PLASMA | R2_SA; | Released | TBD |  | Single |  | Purchase | DIP | 2 | PCS |  |
| 2 |  | 088.0000E.0140 | WASH NYLON WS6-3.2-1 | R2_C; | Released | KANGYANG | WS6-3.2-1 | Single |  | Purchase | DIP | 2 | PCS |  |
| 2 |  | 086.000LQ.0543 | THUMB SCREW PRESSFIT M3 L3 BC | R2_C; | Released | FIVETECH | 27-141-201-5 | Single |  | Purchase | DIP | 2 | PCS |  |
| 16318-SB |  |  |  |  |  |  |  |  |  |  |  |  |  |  |
| 2 |  | 086.6A322.04R5 | SCRW ROUND M2 L3 ZN | R2_SA; | Released | TBD |  | Single |  | Purchase | DIP | 2 | PCS |  |
| 2 |  | B34.01107.0001 | HSINK_60X60X6.5_PUSHPIN_PAD_ACKBAR | R2_C; | Released | CCI | NA | Single |  | Purchase | DIP | 1 | PCS |  |
| 2 |  | B42.0110B.0001 | SPACE SUPPORT TRITON KY | R2_C; | Released | KANGYANG | MSPJ-5V0 | Single |  | Purchase | DIP | 2 | PCS |  |
| 2 |  | B60.0110V.0011 | ASSY NIC CARD LATCH BC MP | R2_C; | Released | FIVETECH | TBD | Single |  | Purchase | DIP | 2 | PCS |  |
| 2 |  | B42.0111K.1001 | CVR XCEDE SIGNAL JX410-50824 MP | R2_C; | Released | TBD |  | Single |  | Purchase | DIP | 1 | PCS |  |
| 3 |  | 087.71242.0465 | NUT TPM M3*0.5*L6 NI EVT | R2_SA;HF_SA; | Released | TBD |  | Single |  | Purchase | SMT | 1 | PCS | NUT1 |
| 16342-SD |  |  |  |  |  |  |  |  |  |  |  |  |  |  |
| 2 |  | B42.0110B.0001 | SPACE SUPPORT TRITON KY | R2_C; | Released | KANGYANG | MSPJ-5V0 | Single |  | Purchase | DIP | 2 | PCS |  |
| 2 |  | B60.0110V.0011 | ASSY NIC CARD LATCH BC MP | R2_C; | Released | FIVETECH | TBD | Single |  | Purchase | DIP | 2 | PCS |  |
| 2 |  | B42.01201.1011 | LATCH M.2 H3.9 FIVETECH 2 | R2_C; | Released | FIVETECH | TBD | Single |  | Purchase | DIP | 2 | PCS |  |
| 2 |  | B42.0111K.1001 | CVR XCEDE SIGNAL JX410-50824 MP | R2_C; | Released | TBD |  | Single |  | Purchase | DIP | 1 | PCS |  |
| 3 |  | 087.71242.0465 | NUT TPM M3*0.5*L6 NI EVT | R2_SA;HF_SA; | Released | TBD |  | Single |  | Purchase | SMT | 1 | PCS | NUT1 |
| 16347-SC |  |  |  |  |  |  |  |  |  |  |  |  |  |  |
|  |  | NA |  |  |  |  |  |  |  |  |  |  |  |  |
| 16369-SD |  |  |  |  |  |  |  |  |  |  |  |  |  |  |
| 3 |  | 086.2AT24.04R6 | THUMB SCREW SMT M3X0.5 L4.6 | R2_SA;HF_SA; | Released | FIVETECH | FIVETECH | Single |  | Purchase | SMT | 1 | PCS | SCW1 |
